# S9S_MB_2U (Grand Teton) — schematic netlist excerpt (pin names and nets, part order shuffled) for the footprints in the layout excerpt that follows; sources: Cadence DE-HDL packaged netlist, KiCad conversion of 03242023_DA0F0TMBIJ0_F0T_Motherboard_J_brd_V01_OCP.brd

J16  SCONN288_ADR50017P087CC  SCONN288_ADR50017-P087CC IO  pkg DDR288S_1-1VXB  page 97
  VIN_BULK0  = P12V_S3_AUX_CPU0_NVDIMM
  RFU0  = TP_CHH_CPU0_DIMM2_FRU_0
  VIN_MGMT  = P3V3_AUX
  HSCL  = I3C_SPD_DDREFGH_CPU0_LVC1_SCL_7
  HSDA  = I3C_SPD_DDREFGH_CPU0_LVC1_SDA
  VSS0  = GND
  DQ0_A  = M_H_CPU0_SA_DQ<0>
  VSS1  = GND
  DQ1_A  = M_H_CPU0_SA_DQ<1>
  VSS2  = GND
  DQS0_A_T  = M_H_CPU0_SA_DQS_DP<0>
  DQS0_A_C  = M_H_CPU0_SA_DQS_DN<0>
  VSS3  = GND
  DQ4_A  = M_H_CPU0_SA_DQ<4>
  VSS4  = GND
  DQ5_A  = M_H_CPU0_SA_DQ<5>
  VSS5  = GND
  DQ8_A  = M_H_CPU0_SA_DQ<8>
  VSS6  = GND
  DQ9_A  = M_H_CPU0_SA_DQ<9>
  VSS7  = GND
  DQS1_A_T  = M_H_CPU0_SA_DQS_DP<1>
  DQS1_A_C  = M_H_CPU0_SA_DQS_DN<1>
  VSS8  = GND
  DQ12_A  = M_H_CPU0_SA_DQ<12>
  VSS9  = GND
  DQ13_A  = M_H_CPU0_SA_DQ<13>
  VSS10  = GND
  DQ16_A  = M_H_CPU0_SA_DQ<16>
  VSS11  = GND
  DQ17_A  = M_H_CPU0_SA_DQ<17>
  VSS12  = GND
  DQS2_A_T  = M_H_CPU0_SA_DQS_DP<2>
  DQS2_A_C  = M_H_CPU0_SA_DQS_DN<2>
  VSS13  = GND
  DQ20_A  = M_H_CPU0_SA_DQ<20>
  VSS14  = GND
  DQ21_A  = M_H_CPU0_SA_DQ<21>
  VSS15  = GND
  DQ24_A  = M_H_CPU0_SA_DQ<24>
  VSS16  = GND
  DQ25_A  = M_H_CPU0_SA_DQ<25>
  VSS17  = GND
  DQS3_A_T  = M_H_CPU0_SA_DQS_DP<3>
  DQS3_A_C  = M_H_CPU0_SA_DQS_DN<3>
  VSS18  = GND
  DQ28_A  = M_H_CPU0_SA_DQ<28>
  VSS19  = GND
  DQ29_A  = M_H_CPU0_SA_DQ<29>
  VSS20  = GND
  CB0_A  = M_H_CPU0_SA_CB<0>
  VSS21  = GND
  CB1_A  = M_H_CPU0_SA_CB<1>
  VSS22  = GND
  DQS4_A_T  = M_H_CPU0_SA_DQS_DP<4>
  DQS4_A_C  = M_H_CPU0_SA_DQS_DN<4>
  VSS23  = GND
  CB4_A  = M_H_CPU0_SA_CB<4>
  VSS24  = GND
  CB5_A  = M_H_CPU0_SA_CB<5>
  VSS25  = GND
  ALERT_N  = M_H_CPU0_ALERT_N
  VSS26  = GND
  CS0_A_N  = M_H_CPU0_SA_CS_N<2>
  VSS27  = GND
  CA0_A  = M_H_CPU0_SA_CA<0>
  VSS28  = GND
  CA2_A  = M_H_CPU0_SA_CA<2>
  VSS29  = GND
  CA4_A  = M_H_CPU0_SA_CA<4>
  VSS30  = GND
  CA6_A  = M_H_CPU0_SA_CA<6>
  VSS31  = GND
  PAR_A  = M_H_CPU0_SA_PAR
  VSS32  = GND
  CA0_B  = M_H_CPU0_SB_CA<0>
  VSS33  = GND
  CA2_B  = M_H_CPU0_SB_CA<2>
  VSS34  = GND
  CA4_B  = M_H_CPU0_SB_CA<4>
  VSS35  = GND
  CA6_B  = M_H_CPU0_SB_CA<6>
  VSS36  = GND
  CS0_B_N  = M_H_CPU0_SB_CS_N<2>
  VSS37  = GND
  \lbd||rsp_a_n\  = M_H_CPU0_SA_RSP<1>
  \lbs||rsp_b_n\  = M_H_CPU0_SB_RSP<1>
  VSS38  = GND
  CB4_B  = M_H_CPU0_SB_CB<4>
  VSS39  = GND
  CB5_B  = M_H_CPU0_SB_CB<5>
  VSS40  = GND
  \dqs9_b_t||tdqs9_b_t||dbi4_b_n\  = M_H_CPU0_SB_DQS_DP<9>
  \dqs9_b_c||tdqs9_b_c\  = M_H_CPU0_SB_DQS_DN<9>
  VSS41  = GND
  CB0_B  = M_H_CPU0_SB_CB<0>
  VSS42  = GND
  CB1_B  = M_H_CPU0_SB_CB<1>
  VSS43  = GND
  DQ0_B  = M_H_CPU0_SB_DQ<0>
  VSS44  = GND
  DQ1_B  = M_H_CPU0_SB_DQ<1>
  VSS45  = GND
  DQS0_B_T  = M_H_CPU0_SB_DQS_DP<0>
  DQS0_B_C  = M_H_CPU0_SB_DQS_DN<0>
  VSS46  = GND
  DQ4_B  = M_H_CPU0_SB_DQ<4>
  VSS47  = GND
  DQ5_B  = M_H_CPU0_SB_DQ<5>
  VSS48  = GND
  DQ8_B  = M_H_CPU0_SB_DQ<8>
  VSS49  = GND
  DQ9_B  = M_H_CPU0_SB_DQ<9>
  VSS50  = GND
  DQS1_B_T  = M_H_CPU0_SB_DQS_DP<1>
  DQS1_B_C  = M_H_CPU0_SB_DQS_DN<1>
  VSS51  = GND
  DQ12_B  = M_H_CPU0_SB_DQ<12>
  VSS52  = GND
  DQ13_B  = M_H_CPU0_SB_DQ<13>
  VSS53  = GND
  DQ16_B  = M_H_CPU0_SB_DQ<16>
  VSS54  = GND
  DQ17_B  = M_H_CPU0_SB_DQ<17>
  VSS55  = GND
  DQS2_B_T  = M_H_CPU0_SB_DQS_DP<2>
  DQS2_B_C  = M_H_CPU0_SB_DQS_DN<2>
  VSS56  = GND
  DQ20_B  = M_H_CPU0_SB_DQ<20>
  VSS57  = GND
  DQ21_B  = M_H_CPU0_SB_DQ<21>
  VSS58  = GND
  DQ24_B  = M_H_CPU0_SB_DQ<24>
  VSS59  = GND
  DQ25_B  = M_H_CPU0_SB_DQ<25>
  VSS60  = GND
  DQS3_B_T  = M_H_CPU0_SB_DQS_DP<3>
  DQS3_B_C  = M_H_CPU0_SB_DQS_DN<3>
  VSS61  = GND
  DQ28_B  = M_H_CPU0_SB_DQ<28>
  VSS62  = GND
  DQ29_B  = M_H_CPU0_SB_DQ<29>
  VSS63  = GND
  RFU1  = TP_CHH_CPU0_DIMM2_FRU_1
  VIN_BULK1  = P12V_S3_AUX_CPU0_NVDIMM
  VIN_BULK2  = P12V_S3_AUX_CPU0_NVDIMM
  \pwr_good||fail_n\  = PWRGD_CHH_CPU0_DIMM2
  HSA  = PD_CHH_CPU0_DIMM2_SAA
  RFU2  = TP_CHH_CPU0_DIMM2_FRU_2
  RFU3  = TP_CHH_CPU0_DIMM2_FRU_3
  VSS64  = GND
  DQ2_A  = M_H_CPU0_SA_DQ<2>
  VSS65  = GND
  DQ3_A  = M_H_CPU0_SA_DQ<3>
  VSS66  = GND
  \dqs5_a_c||tdqs5_a_c||dqs5_a_t||tdqs5_a_t\  = M_H_CPU0_SA_DQS_DN<5>
  \dqs5_a_t||tdqs5_a_t\  = M_H_CPU0_SA_DQS_DP<5>
  VSS67  = GND
  DQ6_A  = M_H_CPU0_SA_DQ<6>
  VSS68  = GND
  DQ7_A  = M_H_CPU0_SA_DQ<7>
  VSS69  = GND
  DQ10_A  = M_H_CPU0_SA_DQ<10>
  VSS70  = GND
  DQ11_A  = M_H_CPU0_SA_DQ<11>
  VSS71  = GND
  \dqs6_a_c||tdqs6_a_c||dqs6_a_t||tdqs6_a_t\  = M_H_CPU0_SA_DQS_DN<6>
  \dqs6_a_t||tdqs6_a_t\  = M_H_CPU0_SA_DQS_DP<6>
  VSS72  = GND
  DQ14_A  = M_H_CPU0_SA_DQ<14>
  VSS73  = GND
  DQ15_A  = M_H_CPU0_SA_DQ<15>
  VSS74  = GND
  DQ18_A  = M_H_CPU0_SA_DQ<18>
  VSS75  = GND
  DQ19_A  = M_H_CPU0_SA_DQ<19>
  VSS76  = GND
  \dqs7_a_c||tdqs7_a_c\  = M_H_CPU0_SA_DQS_DN<7>
  \dqs7_a_t||tdqs7_a_t\  = M_H_CPU0_SA_DQS_DP<7>
  VSS77  = GND
  DQ22_A  = M_H_CPU0_SA_DQ<22>
  VSS78  = GND
  DQ23_A  = M_H_CPU0_SA_DQ<23>
  VSS79  = GND
  DQ26_A  = M_H_CPU0_SA_DQ<26>
  VSS80  = GND
  DQ27_A  = M_H_CPU0_SA_DQ<27>
  VSS81  = GND
  \dqs8_a_c||tdqs8_a_c\  = M_H_CPU0_SA_DQS_DN<8>
  \dqs8_a_t||tdqs8_a_t\  = M_H_CPU0_SA_DQS_DP<8>
  VSS82  = GND
  DQ30_A  = M_H_CPU0_SA_DQ<30>
  VSS83  = GND
  DQ31_A  = M_H_CPU0_SA_DQ<31>
  VSS84  = GND
  CB2_A  = M_H_CPU0_SA_CB<2>
  VSS85  = GND
  CB3_A  = M_H_CPU0_SA_CB<3>
  VSS86  = GND
  \dqs9_a_c||tdqs9_a_c\  = M_H_CPU0_SA_DQS_DN<9>
  \dqs9_a_t||tdqs9_a_t\  = M_H_CPU0_SA_DQS_DP<9>
  VSS87  = GND
  CB6_A  = M_H_CPU0_SA_CB<6>
  VSS88  = GND
  CB7_A  = M_H_CPU0_SA_CB<7>
  VSS89  = GND
  RESET_N  = RST_M_GH_CPU0_FPGA_N
  VSS90  = GND
  CS1_A_N  = M_H_CPU0_SA_CS_N<3>
  VSS91  = GND
  CA1_A  = M_H_CPU0_SA_CA<1>
  VSS92  = GND
  CA3_A  = M_H_CPU0_SA_CA<3>
  VSS93  = GND
  CA5_A  = M_H_CPU0_SA_CA<5>
  VSS94  = GND
  CK_T  = M_H_CPU0_CLK_DP<1>
  CK_C  = M_H_CPU0_CLK_DN<1>
  VSS95  = GND
  RFU4  = TP_CHH_CPU0_DIMM2_FRU_4
  CA1_B  = M_H_CPU0_SB_CA<1>
  VSS96  = GND
  CA3_B  = M_H_CPU0_SB_CA<3>
  VSS97  = GND
  CA5_B  = M_H_CPU0_SB_CA<5>
  VSS98  = GND
  PAR_B  = M_H_CPU0_SB_PAR
  VSS99  = GND
  CS1_B_N  = M_H_CPU0_SB_CS_N<3>
  VSS100  = GND
  RFU5  = TP_CHH_CPU0_DIMM2_FRU_5
  RFU6  = TP_CHH_CPU0_DIMM2_FRU_6
  VSS101  = GND
  CB6_B  = M_H_CPU0_SB_CB<6>
  VSS102  = GND
  CB7_B  = M_H_CPU0_SB_CB<7>
  VSS103  = GND
  DQS4_B_C  = M_H_CPU0_SB_DQS_DN<4>
  DQS4_B_T  = M_H_CPU0_SB_DQS_DP<4>
  VSS104  = GND
  CB2_B  = M_H_CPU0_SB_CB<2>
  VSS105  = GND
  CB3_B  = M_H_CPU0_SB_CB<3>
  VSS106  = GND
  DQ2_B  = M_H_CPU0_SB_DQ<2>
  VSS107  = GND
  DQ3_B  = M_H_CPU0_SB_DQ<3>
  VSS108  = GND
  \dqs5_b_c||tdqs5_b_c\  = M_H_CPU0_SB_DQS_DN<5>
  \dqs5_b_t||tdqs5_b_t\  = M_H_CPU0_SB_DQS_DP<5>
  VSS109  = GND
  DQ6_B  = M_H_CPU0_SB_DQ<6>
  VSS110  = GND
  DQ7_B  = M_H_CPU0_SB_DQ<7>
  VSS111  = GND
  DQ10_B  = M_H_CPU0_SB_DQ<10>
  VSS112  = GND
  DQ11_B  = M_H_CPU0_SB_DQ<11>
  VSS113  = GND
  \dqs6_b_c||tdqs6_b_c\  = M_H_CPU0_SB_DQS_DN<6>
  \dqs6_b_t||tdqs6_b_t\  = M_H_CPU0_SB_DQS_DP<6>
  VSS114  = GND
  DQ14_B  = M_H_CPU0_SB_DQ<14>
  VSS115  = GND
  DQ15_B  = M_H_CPU0_SB_DQ<15>
  VSS116  = GND
  DQ18_B  = M_H_CPU0_SB_DQ<18>
  VSS117  = GND
  DQ19_B  = M_H_CPU0_SB_DQ<19>
  VSS118  = GND
  \dqs7_b_c||tdqs7_b_c\  = M_H_CPU0_SB_DQS_DN<7>
  \dqs7_b_t||tdqs7_b_t\  = M_H_CPU0_SB_DQS_DP<7>
  VSS119  = GND
  DQ22_B  = M_H_CPU0_SB_DQ<22>
  VSS120  = GND
  DQ23_B  = M_H_CPU0_SB_DQ<23>
  VSS121  = GND
  DQ26_B  = M_H_CPU0_SB_DQ<26>
  VSS122  = GND
  DQ27_B  = M_H_CPU0_SB_DQ<27>
  VSS123  = GND
  \dqs8_b_c||tdqs8_b_c\  = M_H_CPU0_SB_DQS_DN<8>
  \dqs8_b_t||tdqs8_b_t\  = M_H_CPU0_SB_DQS_DP<8>
  VSS124  = GND
  DQ30_B  = M_H_CPU0_SB_DQ<30>
  VSS125  = GND
  DQ31_B  = M_H_CPU0_SB_DQ<31>
  VSS126  = GND
  G1  = GND
  G2  = GND
  G3  = GND

(kicad_pcb
	(version 20260206)
	(generator "pcbnew")
	(generator_version "10.0")
	(general
		(thickness 1.6)
		(legacy_teardrops no)
	)
	(paper "A4")
	(title_block
		(title "03242023_DA0F0TMBIJ0_F0T_Motherboard_J_brd_V01_OCP.brd")
		(comment 1 "Grand Teton / footprint 1690 of 6105 (J16), pads 1-45 of 291")
	)
	(layers
		(0 "F.Cu" signal "TOP")
		(4 "In1.Cu" signal "GND")
		(6 "In2.Cu" signal "IN1")
		(8 "In3.Cu" signal "GND1")
		(10 "In4.Cu" signal "IN2")
		(12 "In5.Cu" signal "GND2")
		(14 "In6.Cu" signal "IN3")
		(16 "In7.Cu" signal "GND3")
		(18 "In8.Cu" signal "VCC")
		(20 "In9.Cu" signal "VCC1")
		(22 "In10.Cu" signal "GND4")
		(24 "In11.Cu" signal "IN4")
		(26 "In12.Cu" signal "GND5")
		(28 "In13.Cu" signal "IN5")
		(30 "In14.Cu" signal "GND6")
		(32 "In15.Cu" signal "IN6")
		(34 "In16.Cu" signal "GND7")
		(2 "B.Cu" signal "BOTTOM")
		(9 "F.Adhes" user "F.Adhesive")
		(11 "B.Adhes" user "B.Adhesive")
		(13 "F.Paste" user "Package Geometry/Pastemask Top")
		(15 "B.Paste" user "Package Geometry/Pastemask Bottom")
		(5 "F.SilkS" user "Ref Des/Silkscreen Top")
		(7 "B.SilkS" user "Ref Des/Silkscreen Bottom")
		(1 "F.Mask" user "Board Geometry/Soldermask Top")
		(3 "B.Mask" user "Board Geometry/Soldermask Bottom")
		(17 "Dwgs.User" user "User.Drawings")
		(19 "Cmts.User" user "User.Comments")
		(21 "Eco1.User" user "User.Eco1")
		(23 "Eco2.User" user "User.Eco2")
		(25 "Edge.Cuts" user "Board Geometry/Outline")
		(27 "Margin" user)
		(31 "F.CrtYd" user "Package Geometry/Place Bound Top")
		(29 "B.CrtYd" user "Package Geometry/Place Bound Bottom")
		(35 "F.Fab" user "Ref Des/Assembly Top")
		(33 "B.Fab" user "Ref Des/Assembly Bottom")
	)
	(footprint ""
		(layer "F.Cu")
		(at 454.066148 -258.091686)
		(property "Reference" "J16"
			(at -0.279908 -81.779872 0)
			(unlocked yes)
			(layer "F.SilkS")
			(effects
				(font
					(size 0.7874 0.5842)
					(thickness 0.1524)
				)
				(justify left)
			)
		)
		(property "Value" ""
			(at 0 0 0)
			(layer "F.Fab")
			(effects
				(font
					(size 1.27 1.27)
				)
			)
		)
		(duplicate_pad_numbers_are_jumpers no)
		(pad "1" smd rect
			(at -2.050034 -63.324994 270)
			(size 0.519938 1.4986)
			(layers "F.Cu" "F.Mask" "F.Paste")
			(net "P12V_S3_AUX_CPU0_NVDIMM")
		)
		(pad "2" smd rect
			(at -2.050034 -62.47511 270)
			(size 0.519938 1.4986)
			(layers "F.Cu" "F.Mask" "F.Paste")
			(net "TP_CHH_CPU0_DIMM2_FRU_0")
		)
		(pad "3" smd rect
			(at -2.050034 -61.624972 270)
			(size 0.519938 1.4986)
			(layers "F.Cu" "F.Mask" "F.Paste")
			(net "P3V3_AUX")
		)
		(pad "4" smd rect
			(at -2.050034 -60.775088 270)
			(size 0.519938 1.4986)
			(layers "F.Cu" "F.Mask" "F.Paste")
			(net "I3C_SPD_DDREFGH_CPU0_LVC1_SCL_7")
		)
		(pad "5" smd rect
			(at -2.050034 -59.92495 270)
			(size 0.519938 1.4986)
			(layers "F.Cu" "F.Mask" "F.Paste")
			(net "I3C_SPD_DDREFGH_CPU0_LVC1_SDA")
		)
		(pad "6" smd rect
			(at -2.050034 -59.075066 270)
			(size 0.519938 1.4986)
			(layers "F.Cu" "F.Mask" "F.Paste")
			(net "GND")
		)
		(pad "7" smd rect
			(at -2.050034 -58.224928 270)
			(size 0.519938 1.4986)
			(layers "F.Cu" "F.Mask" "F.Paste")
			(net "M_H_CPU0_SA_DQ<0>")
		)
		(pad "8" smd rect
			(at -2.050034 -57.375044 270)
			(size 0.519938 1.4986)
			(layers "F.Cu" "F.Mask" "F.Paste")
			(net "GND")
		)
		(pad "9" smd rect
			(at -2.050034 -56.524906 270)
			(size 0.519938 1.4986)
			(layers "F.Cu" "F.Mask" "F.Paste")
			(net "M_H_CPU0_SA_DQ<1>")
		)
		(pad "10" smd rect
			(at -2.050034 -55.675022 270)
			(size 0.519938 1.4986)
			(layers "F.Cu" "F.Mask" "F.Paste")
			(net "GND")
		)
		(pad "11" smd rect
			(at -2.050034 -54.824884 270)
			(size 0.519938 1.4986)
			(layers "F.Cu" "F.Mask" "F.Paste")
			(net "M_H_CPU0_SA_DQS_DP<0>")
		)
		(pad "12" smd rect
			(at -2.050034 -53.975 270)
			(size 0.519938 1.4986)
			(layers "F.Cu" "F.Mask" "F.Paste")
			(net "M_H_CPU0_SA_DQS_DN<0>")
		)
		(pad "13" smd rect
			(at -2.050034 -53.125116 270)
			(size 0.519938 1.4986)
			(layers "F.Cu" "F.Mask" "F.Paste")
			(net "GND")
		)
		(pad "14" smd rect
			(at -2.050034 -52.274978 270)
			(size 0.519938 1.4986)
			(layers "F.Cu" "F.Mask" "F.Paste")
			(net "M_H_CPU0_SA_DQ<4>")
		)
		(pad "15" smd rect
			(at -2.050034 -51.425094 270)
			(size 0.519938 1.4986)
			(layers "F.Cu" "F.Mask" "F.Paste")
			(net "GND")
		)
		(pad "16" smd rect
			(at -2.050034 -50.574956 270)
			(size 0.519938 1.4986)
			(layers "F.Cu" "F.Mask" "F.Paste")
			(net "M_H_CPU0_SA_DQ<5>")
		)
		(pad "17" smd rect
			(at -2.050034 -49.725072 270)
			(size 0.519938 1.4986)
			(layers "F.Cu" "F.Mask" "F.Paste")
			(net "GND")
		)
		(pad "18" smd rect
			(at -2.050034 -48.874934 270)
			(size 0.519938 1.4986)
			(layers "F.Cu" "F.Mask" "F.Paste")
			(net "M_H_CPU0_SA_DQ<8>")
		)
		(pad "19" smd rect
			(at -2.050034 -48.02505 270)
			(size 0.519938 1.4986)
			(layers "F.Cu" "F.Mask" "F.Paste")
			(net "GND")
		)
		(pad "20" smd rect
			(at -2.050034 -47.174912 270)
			(size 0.519938 1.4986)
			(layers "F.Cu" "F.Mask" "F.Paste")
			(net "M_H_CPU0_SA_DQ<9>")
		)
		(pad "21" smd rect
			(at -2.050034 -46.325028 270)
			(size 0.519938 1.4986)
			(layers "F.Cu" "F.Mask" "F.Paste")
			(net "GND")
		)
		(pad "22" smd rect
			(at -2.050034 -45.47489 270)
			(size 0.519938 1.4986)
			(layers "F.Cu" "F.Mask" "F.Paste")
			(net "M_H_CPU0_SA_DQS_DP<1>")
		)
		(pad "23" smd rect
			(at -2.050034 -44.625006 270)
			(size 0.519938 1.4986)
			(layers "F.Cu" "F.Mask" "F.Paste")
			(net "M_H_CPU0_SA_DQS_DN<1>")
		)
		(pad "24" smd rect
			(at -2.050034 -43.775122 270)
			(size 0.519938 1.4986)
			(layers "F.Cu" "F.Mask" "F.Paste")
			(net "GND")
		)
		(pad "25" smd rect
			(at -2.050034 -42.924984 270)
			(size 0.519938 1.4986)
			(layers "F.Cu" "F.Mask" "F.Paste")
			(net "M_H_CPU0_SA_DQ<12>")
		)
		(pad "26" smd rect
			(at -2.050034 -42.0751 270)
			(size 0.519938 1.4986)
			(layers "F.Cu" "F.Mask" "F.Paste")
			(net "GND")
		)
		(pad "27" smd rect
			(at -2.050034 -41.224962 270)
			(size 0.519938 1.4986)
			(layers "F.Cu" "F.Mask" "F.Paste")
			(net "M_H_CPU0_SA_DQ<13>")
		)
		(pad "28" smd rect
			(at -2.050034 -40.375078 270)
			(size 0.519938 1.4986)
			(layers "F.Cu" "F.Mask" "F.Paste")
			(net "GND")
		)
		(pad "29" smd rect
			(at -2.050034 -39.52494 270)
			(size 0.519938 1.4986)
			(layers "F.Cu" "F.Mask" "F.Paste")
			(net "M_H_CPU0_SA_DQ<16>")
		)
		(pad "30" smd rect
			(at -2.050034 -38.675056 270)
			(size 0.519938 1.4986)
			(layers "F.Cu" "F.Mask" "F.Paste")
			(net "GND")
		)
		(pad "31" smd rect
			(at -2.050034 -37.824918 270)
			(size 0.519938 1.4986)
			(layers "F.Cu" "F.Mask" "F.Paste")
			(net "M_H_CPU0_SA_DQ<17>")
		)
		(pad "32" smd rect
			(at -2.050034 -36.975034 270)
			(size 0.519938 1.4986)
			(layers "F.Cu" "F.Mask" "F.Paste")
			(net "GND")
		)
		(pad "33" smd rect
			(at -2.050034 -36.124896 270)
			(size 0.519938 1.4986)
			(layers "F.Cu" "F.Mask" "F.Paste")
			(net "M_H_CPU0_SA_DQS_DP<2>")
		)
		(pad "34" smd rect
			(at -2.050034 -35.275012 270)
			(size 0.519938 1.4986)
			(layers "F.Cu" "F.Mask" "F.Paste")
			(net "M_H_CPU0_SA_DQS_DN<2>")
		)
		(pad "35" smd rect
			(at -2.050034 -34.425128 270)
			(size 0.519938 1.4986)
			(layers "F.Cu" "F.Mask" "F.Paste")
			(net "GND")
		)
		(pad "36" smd rect
			(at -2.050034 -33.57499 270)
			(size 0.519938 1.4986)
			(layers "F.Cu" "F.Mask" "F.Paste")
			(net "M_H_CPU0_SA_DQ<20>")
		)
		(pad "37" smd rect
			(at -2.050034 -32.725106 270)
			(size 0.519938 1.4986)
			(layers "F.Cu" "F.Mask" "F.Paste")
			(net "GND")
		)
		(pad "38" smd rect
			(at -2.050034 -31.874968 270)
			(size 0.519938 1.4986)
			(layers "F.Cu" "F.Mask" "F.Paste")
			(net "M_H_CPU0_SA_DQ<21>")
		)
		(pad "39" smd rect
			(at -2.050034 -31.025084 270)
			(size 0.519938 1.4986)
			(layers "F.Cu" "F.Mask" "F.Paste")
			(net "GND")
		)
		(pad "40" smd rect
			(at -2.050034 -30.174946 270)
			(size 0.519938 1.4986)
			(layers "F.Cu" "F.Mask" "F.Paste")
			(net "M_H_CPU0_SA_DQ<24>")
		)
		(pad "41" smd rect
			(at -2.050034 -29.325062 270)
			(size 0.519938 1.4986)
			(layers "F.Cu" "F.Mask" "F.Paste")
			(net "GND")
		)
		(pad "42" smd rect
			(at -2.050034 -28.474924 270)
			(size 0.519938 1.4986)
			(layers "F.Cu" "F.Mask" "F.Paste")
			(net "M_H_CPU0_SA_DQ<25>")
		)
		(pad "43" smd rect
			(at -2.050034 -27.62504 270)
			(size 0.519938 1.4986)
			(layers "F.Cu" "F.Mask" "F.Paste")
			(net "GND")
		)
		(pad "44" smd rect
			(at -2.050034 -26.774902 270)
			(size 0.519938 1.4986)
			(layers "F.Cu" "F.Mask" "F.Paste")
			(net "M_H_CPU0_SA_DQS_DP<3>")
		)
		(pad "45" smd rect
			(at -2.050034 -25.925018 270)
			(size 0.519938 1.4986)
			(layers "F.Cu" "F.Mask" "F.Paste")
			(net "M_H_CPU0_SA_DQS_DN<3>")
		)
	)
)
